(kicad_pcb
	(version 20260206)
	(generator "pcbnew")
	(generator_version "10.0")
	(general
		(thickness 1.6)
		(legacy_teardrops no)
	)
	(paper "A4")
	(title_block
		(title "v2-pdb — ms_pdb_v2.brd")
		(comment 1 "Open CloudServer (Microsoft) / footprints 221-223 of 348")
	)
	(layers
		(0 "F.Cu" signal "TOP")
		(4 "In1.Cu" signal "GND")
		(6 "In2.Cu" signal "IN1")
		(8 "In3.Cu" signal "VCC")
		(10 "In4.Cu" signal "VCC1")
		(12 "In5.Cu" signal "IN2")
		(14 "In6.Cu" signal "GND1")
		(2 "B.Cu" signal "BOTTOM")
		(9 "F.Adhes" user "F.Adhesive")
		(11 "B.Adhes" user "B.Adhesive")
		(13 "F.Paste" user "Package Geometry/Pastemask Top")
		(15 "B.Paste" user "Package Geometry/Pastemask Bottom")
		(5 "F.SilkS" user "Ref Des/Silkscreen Top")
		(7 "B.SilkS" user "Ref Des/Silkscreen Bottom")
		(1 "F.Mask" user "Board Geometry/Soldermask Top")
		(3 "B.Mask" user "Board Geometry/Soldermask Bottom")
		(17 "Dwgs.User" user "User.Drawings")
		(19 "Cmts.User" user "User.Comments")
		(21 "Eco1.User" user "User.Eco1")
		(23 "Eco2.User" user "User.Eco2")
		(25 "Edge.Cuts" user "Board Geometry/Outline")
		(27 "Margin" user)
		(31 "F.CrtYd" user "Package Geometry/Place Bound Top")
		(29 "B.CrtYd" user "Package Geometry/Place Bound Bottom")
		(35 "F.Fab" user "Ref Des/Assembly Top")
		(33 "B.Fab" user "Ref Des/Assembly Bottom")
	)
	(footprint ""
		(layer "F.Cu")
		(at 39.462964 -21.994368 90)
		(property "Reference" "R110"
			(at -0.675132 1.446022 0)
			(unlocked yes)
			(layer "F.SilkS")
			(effects
				(font
					(size 0.7874 0.5842)
					(thickness 0.1524)
				)
				(justify left)
			)
		)
		(property "Value" ""
			(at 0 0 90)
			(layer "F.Fab")
			(effects
				(font
					(size 1.27 1.27)
				)
			)
		)
		(duplicate_pad_numbers_are_jumpers no)
		(fp_line
			(start 0.7874 -0.4064)
			(end 0.7874 0.4064)
			(stroke
				(width 0.1524)
				(type default)
			)
			(layer "F.SilkS")
		)
		(fp_line
			(start -0.7874 -0.4064)
			(end 0.7874 -0.4064)
			(stroke
				(width 0.1524)
				(type default)
			)
			(layer "F.SilkS")
		)
		(fp_line
			(start 0.7874 0.4064)
			(end -0.7874 0.4064)
			(stroke
				(width 0.1524)
				(type default)
			)
			(layer "F.SilkS")
		)
		(fp_line
			(start -0.7874 0.4064)
			(end -0.7874 -0.4064)
			(stroke
				(width 0.1524)
				(type default)
			)
			(layer "F.SilkS")
		)
		(fp_poly
			(pts
				(xy -0.508 0.2794) (xy -0.508 0.2286) (xy -0.635 0.2286) (xy -0.635 -0.254) (xy -0.5334 -0.254)
				(xy -0.5334 -0.2794) (xy 0.5334 -0.2794) (xy 0.5334 -0.254) (xy 0.635 -0.254) (xy 0.635 0.254) (xy 0.5334 0.254)
				(xy 0.5334 0.2794)
			)
			(stroke
				(width 0)
				(type default)
			)
			(fill no)
			(layer "F.CrtYd")
		)
		(pad "1" smd rect
			(at 0.40005 0 90)
			(size 0.4572 0.508)
			(layers "F.Cu" "F.Mask" "F.Paste")
			(net "PSU1_REMOTE_P")
		)
		(pad "2" smd rect
			(at -0.40005 0 90)
			(size 0.4572 0.508)
			(layers "F.Cu" "F.Mask" "F.Paste")
			(net "PSU1_REMOTE_R2_P")
		)
	)
	(footprint ""
		(layer "F.Cu")
		(at 15.540736 -451.706234)
		(property "Reference" "C90"
			(at -1.292098 -3.46837 0)
			(unlocked yes)
			(layer "F.SilkS")
			(effects
				(font
					(size 0.7874 0.5842)
					(thickness 0.1524)
				)
				(justify left)
			)
		)
		(property "Value" ""
			(at 0 0 0)
			(layer "F.Fab")
			(effects
				(font
					(size 1.27 1.27)
				)
			)
		)
		(duplicate_pad_numbers_are_jumpers no)
		(fp_line
			(start -0.7874 -0.4064)
			(end 0.7874 -0.4064)
			(stroke
				(width 0.1524)
				(type default)
			)
			(layer "F.SilkS")
		)
		(fp_line
			(start -0.7874 0.4064)
			(end -0.7874 -0.4064)
			(stroke
				(width 0.1524)
				(type default)
			)
			(layer "F.SilkS")
		)
		(fp_line
			(start 0 0.381)
			(end 0 -0.381)
			(stroke
				(width 0.1524)
				(type default)
			)
			(layer "F.SilkS")
		)
		(fp_line
			(start 0.7874 -0.4064)
			(end 0.7874 0.4064)
			(stroke
				(width 0.1524)
				(type default)
			)
			(layer "F.SilkS")
		)
		(fp_line
			(start 0.7874 0.4064)
			(end -0.7874 0.4064)
			(stroke
				(width 0.1524)
				(type default)
			)
			(layer "F.SilkS")
		)
		(fp_poly
			(pts
				(xy -0.5334 0.254) (xy -0.635 0.254) (xy -0.635 0.2286) (xy -0.635 -0.254) (xy -0.5334 -0.254) (xy -0.5334 -0.2794)
				(xy 0.5334 -0.2794) (xy 0.5334 -0.254) (xy 0.635 -0.254) (xy 0.635 0.254) (xy 0.5334 0.254) (xy 0.5334 0.2794)
				(xy -0.508 0.2794) (xy -0.5334 0.2794)
			)
			(stroke
				(width 0)
				(type default)
			)
			(fill no)
			(layer "F.CrtYd")
		)
		(pad "1" smd rect
			(at 0.40005 0)
			(size 0.4572 0.508)
			(layers "F.Cu" "F.Mask" "F.Paste")
			(net "P12V")
		)
		(pad "2" smd rect
			(at -0.40005 0)
			(size 0.4572 0.508)
			(layers "F.Cu" "F.Mask" "F.Paste")
			(net "GND")
		)
	)
	(footprint ""
		(layer "F.Cu")
		(at 67.92468 -38.821106 90)
		(property "Reference" "C13"
			(at 1.149604 -0.056134 90)
			(unlocked yes)
			(layer "F.SilkS")
			(effects
				(font
					(size 0.7874 0.5842)
					(thickness 0.1524)
				)
				(justify left)
			)
		)
		(property "Value" ""
			(at 0 0 90)
			(layer "F.Fab")
			(effects
				(font
					(size 1.27 1.27)
				)
			)
		)
		(duplicate_pad_numbers_are_jumpers no)
		(fp_line
			(start 0.7874 -0.4064)
			(end 0.7874 0.4064)
			(stroke
				(width 0.1524)
				(type default)
			)
			(layer "F.SilkS")
		)
		(fp_line
			(start -0.7874 -0.4064)
			(end 0.7874 -0.4064)
			(stroke
				(width 0.1524)
				(type default)
			)
			(layer "F.SilkS")
		)
		(fp_line
			(start 0 0.381)
			(end 0 -0.381)
			(stroke
				(width 0.1524)
				(type default)
			)
			(layer "F.SilkS")
		)
		(fp_line
			(start 0.7874 0.4064)
			(end -0.7874 0.4064)
			(stroke
				(width 0.1524)
				(type default)
			)
			(layer "F.SilkS")
		)
		(fp_line
			(start -0.7874 0.4064)
			(end -0.7874 -0.4064)
			(stroke
				(width 0.1524)
				(type default)
			)
			(layer "F.SilkS")
		)
		(fp_poly
			(pts
				(xy -0.5334 0.254) (xy -0.635 0.254) (xy -0.635 0.2286) (xy -0.635 -0.254) (xy -0.5334 -0.254) (xy -0.5334 -0.2794)
				(xy 0.5334 -0.2794) (xy 0.5334 -0.254) (xy 0.635 -0.254) (xy 0.635 0.254) (xy 0.5334 0.254) (xy 0.5334 0.2794)
				(xy -0.508 0.2794) (xy -0.5334 0.2794)
			)
			(stroke
				(width 0)
				(type default)
			)
			(fill no)
			(layer "F.CrtYd")
		)
		(pad "1" smd rect
			(at 0.40005 0 90)
			(size 0.4572 0.508)
			(layers "F.Cu" "F.Mask" "F.Paste")
			(net "P12V")
		)
		(pad "2" smd rect
			(at -0.40005 0 90)
			(size 0.4572 0.508)
			(layers "F.Cu" "F.Mask" "F.Paste")
			(net "GND")
		)
	)
)
